FILE_TYPE = MULTI_PHYS_TABLE;

PART 'SN74AUC2G66DCTR'

{========================================================================================}
:VALUE             | PART_TYPE | MATERIAL | PART_NUMBER    = STANDARD | LIFECYCLE      | PART_NUMBER   | JEDEC_TYPE | DESCRIPTION                           | MANUFTR | MANUF_PN          | RD_CMPLS_LVL | CMPLS_LVL | FROM_PJ       | CLASS | DIP_SMD | DATA                  | EE_CHECK_LIST | FP_ECN | PSL | CREATOR | STATUS | MSD | ESD_CDM | ESD_HBM | ESD_MM | PIN_LENGTH_SHORT_PIN | PIN_LENGTH_LONG_PIN | CREATEDAY  ;
{========================================================================================}
 'SN74AUC2G66DCTR' | 'SMLF'    | 'IC'     | 'AL2G0066C00'(!) = ''       | ''               | 'AL2G0066C00' |'SSOP8'| 'IC OTHER(8P) SN74AUC2G66DCTR (SSOP)' | 'TIC'   | 'SN74AUC2G66DCTR' | 'EP(V1)'     | 'EP(V1)'  | 'S2C-WEITING' | 'IC'  | ''      | 'TIC_SN74AUC2G66.pdf' | ''            | ''     | ''  | ''      | ''     | ''  | ''      | ''      | ''     | ''                   | ''                  | '20100429'
 'SN74AUC2G66DCTR' | 'SMLF'    | 'EMPTY'  | 'AL2G0066C00'(!) = ''       | ''               | 'AL2G0066C00' |'SSOP8'| 'IC OTHER(8P) SN74AUC2G66DCTR (SSOP)' | 'TIC'   | 'SN74AUC2G66DCTR' | 'EP(V1)'     | 'EP(V1)'  | 'S2C-WEITING' | 'IC'  | ''      | 'TIC_SN74AUC2G66.pdf' | ''            | ''     | ''  | ''      | ''     | ''  | ''      | ''      | ''     | ''                   | ''                  | '20100429'

END_PART

END.

